(kicad_pcb
	(version 20241229)
	(generator "pcbnew")
	(generator_version "9.0")
	(general
		(thickness 1.62)
		(legacy_teardrops no)
	)
	(paper "A4")
	(title_block
		(title "OCuLink to 10GbE adapter")
		(date "2026-02-23")
		(rev "1.1.0")
		(company "Antmicro Ltd")
		(comment 1 "www.antmicro.com")
		(comment 9 "footprints 357-362 of 510")
	)
	(layers
		(0 "F.Cu" signal)
		(4 "In1.Cu" signal)
		(6 "In2.Cu" signal)
		(8 "In3.Cu" signal)
		(10 "In4.Cu" signal)
		(12 "In5.Cu" signal)
		(14 "In6.Cu" signal)
		(2 "B.Cu" signal)
		(9 "F.Adhes" user "F.Adhesive")
		(11 "B.Adhes" user "B.Adhesive")
		(13 "F.Paste" user)
		(15 "B.Paste" user)
		(5 "F.SilkS" user "F.Silkscreen")
		(7 "B.SilkS" user "B.Silkscreen")
		(1 "F.Mask" user)
		(3 "B.Mask" user)
		(17 "Dwgs.User" user "User.Drawings")
		(19 "Cmts.User" user "User.Comments")
		(21 "Eco1.User" user "User.Eco1")
		(23 "Eco2.User" user "User.Eco2")
		(25 "Edge.Cuts" user)
		(27 "Margin" user)
		(31 "F.CrtYd" user "F.Courtyard")
		(29 "B.CrtYd" user "B.Courtyard")
		(35 "F.Fab" user)
		(33 "B.Fab" user)
	)
	(footprint "antmicro-footprints:C_0402_1005Metric"
		(layer "B.Cu")
		(at 95.48 145.34 -90)
		(descr "Capacitor SMD 0402")
		(tags "capacitor SMD 0402")
		(property "Reference" "C61"
			(at -2.89 -0.44 90)
			(layer "B.SilkS")
			(effects
				(font
					(size 0.7 0.7)
					(thickness 0.15)
				)
				(justify left bottom mirror)
			)
		)
		(property "Value" "C_470p_0402"
			(at -1.022927 -2.155213 90)
			(layer "B.Fab")
			(hide yes)
			(effects
				(font
					(size 0.7 0.7)
					(thickness 0.15)
				)
				(justify left bottom mirror)
			)
		)
		(property "Datasheet" "https://www.passivecomponent.com/wp-content/uploads/datasheet/WTC_MLCC_General_Purpose.pdf"
			(at 0 0 90)
			(layer "B.Fab")
			(hide yes)
			(effects
				(font
					(size 1.27 1.27)
					(thickness 0.15)
				)
				(justify mirror)
			)
		)
		(property "Description" "SMD Multilayer Ceramic Capacitor, General Purpose, 470 pF, 25 V, 0402 [1005 Metric], ± 10%, X7R"
			(at 0 0 90)
			(layer "B.Fab")
			(hide yes)
			(effects
				(font
					(size 1.27 1.27)
					(thickness 0.15)
				)
				(justify mirror)
			)
		)
		(property "MPN" "0402B471K250CT"
			(at 0 0 270)
			(unlocked yes)
			(layer "B.Fab")
			(hide yes)
			(effects
				(font
					(size 1 1)
					(thickness 0.15)
				)
				(justify mirror)
			)
		)
		(property "Manufacturer" "Walsin"
			(at 0 0 270)
			(unlocked yes)
			(layer "B.Fab")
			(hide yes)
			(effects
				(font
					(size 1 1)
					(thickness 0.15)
				)
				(justify mirror)
			)
		)
		(property "License" "Apache-2.0"
			(at 0 0 270)
			(unlocked yes)
			(layer "B.Fab")
			(hide yes)
			(effects
				(font
					(size 1 1)
					(thickness 0.15)
				)
				(justify mirror)
			)
		)
		(property "Author" "Antmicro"
			(at 0 0 270)
			(unlocked yes)
			(layer "B.Fab")
			(hide yes)
			(effects
				(font
					(size 1 1)
					(thickness 0.15)
				)
				(justify mirror)
			)
		)
		(property "Val" "470p"
			(at 0 0 270)
			(unlocked yes)
			(layer "B.Fab")
			(hide yes)
			(effects
				(font
					(size 1 1)
					(thickness 0.15)
				)
				(justify mirror)
			)
		)
		(property "Voltage" "25V"
			(at 0 0 270)
			(unlocked yes)
			(layer "B.Fab")
			(hide yes)
			(effects
				(font
					(size 1 1)
					(thickness 0.15)
				)
				(justify mirror)
			)
		)
		(property "Dielectric" "X7R"
			(at 0 0 270)
			(unlocked yes)
			(layer "B.Fab")
			(hide yes)
			(effects
				(font
					(size 1 1)
					(thickness 0.15)
				)
				(justify mirror)
			)
		)
		(sheetname "/2xRJ45/")
		(sheetfile "2xrj45.kicad_sch")
		(attr smd)
		(fp_rect
			(start -0.925 0.47)
			(end 0.925 -0.47)
			(stroke
				(width 0.05)
				(type default)
			)
			(fill no)
			(layer "B.CrtYd")
		)
		(fp_line
			(start -0.494 0.25)
			(end 0.504 0.25)
			(stroke
				(width 0.15)
				(type solid)
			)
			(layer "B.Fab")
		)
		(fp_line
			(start 0.504 0.25)
			(end 0.504 -0.248)
			(stroke
				(width 0.15)
				(type solid)
			)
			(layer "B.Fab")
		)
		(fp_line
			(start -0.494 -0.248)
			(end -0.494 0.25)
			(stroke
				(width 0.15)
				(type solid)
			)
			(layer "B.Fab")
		)
		(fp_line
			(start 0.504 -0.248)
			(end -0.494 -0.248)
			(stroke
				(width 0.15)
				(type solid)
			)
			(layer "B.Fab")
		)
		(pad "1" smd roundrect
			(at -0.48 0 270)
			(size 0.59 0.64)
			(layers "B.Cu" "B.Mask" "B.Paste")
			(roundrect_rratio 0.25)
			(net 28 "GND")
			(pintype "passive")
		)
		(pad "2" smd roundrect
			(at 0.48 0 270)
			(size 0.59 0.64)
			(layers "B.Cu" "B.Mask" "B.Paste")
			(roundrect_rratio 0.25)
			(net 64 "Net-(J6-LED_YG_G-)")
			(pintype "passive")
		)
	)
	(footprint "antmicro-footprints:C_0402_1005Metric"
		(layer "B.Cu")
		(at 89.225 102 90)
		(descr "Capacitor SMD 0402")
		(tags "capacitor SMD 0402")
		(property "Reference" "C92"
			(at 9.09 -0.447343 90)
			(layer "B.SilkS")
			(effects
				(font
					(size 0.7 0.7)
					(thickness 0.15)
				)
				(justify right top mirror)
			)
		)
		(property "Value" "C_1u_25V_0402"
			(at -1.022927 -2.155213 90)
			(layer "B.Fab")
			(hide yes)
			(effects
				(font
					(size 0.7 0.7)
					(thickness 0.15)
				)
				(justify right top mirror)
			)
		)
		(property "Datasheet" "https://www.murata.com/products/productdetail?partno=GRM155R61E105KE11%23"
			(at 0 0 90)
			(layer "B.Fab")
			(hide yes)
			(effects
				(font
					(size 1.27 1.27)
					(thickness 0.15)
				)
				(justify mirror)
			)
		)
		(property "Description" "SMD Multilayer Ceramic Capacitor, 1 µF, 25 V, 0402 [1005 Metric], ± 10%, X5R, GRM Series"
			(at 0 0 90)
			(layer "B.Fab")
			(hide yes)
			(effects
				(font
					(size 1.27 1.27)
					(thickness 0.15)
				)
				(justify mirror)
			)
		)
		(property "MPN" "GRM155R61E105KE11J"
			(at 0 0 90)
			(unlocked yes)
			(layer "B.Fab")
			(hide yes)
			(effects
				(font
					(size 1 1)
					(thickness 0.15)
				)
				(justify mirror)
			)
		)
		(property "Manufacturer" "Murata"
			(at 0 0 90)
			(unlocked yes)
			(layer "B.Fab")
			(hide yes)
			(effects
				(font
					(size 1 1)
					(thickness 0.15)
				)
				(justify mirror)
			)
		)
		(property "License" "Apache-2.0"
			(at 0 0 90)
			(unlocked yes)
			(layer "B.Fab")
			(hide yes)
			(effects
				(font
					(size 1 1)
					(thickness 0.15)
				)
				(justify mirror)
			)
		)
		(property "Author" "Antmicro"
			(at 0 0 90)
			(unlocked yes)
			(layer "B.Fab")
			(hide yes)
			(effects
				(font
					(size 1 1)
					(thickness 0.15)
				)
				(justify mirror)
			)
		)
		(property "Val" "1u"
			(at 0 0 90)
			(unlocked yes)
			(layer "B.Fab")
			(hide yes)
			(effects
				(font
					(size 1 1)
					(thickness 0.15)
				)
				(justify mirror)
			)
		)
		(property "Voltage" "25V"
			(at 0 0 90)
			(unlocked yes)
			(layer "B.Fab")
			(hide yes)
			(effects
				(font
					(size 1 1)
					(thickness 0.15)
				)
				(justify mirror)
			)
		)
		(property "Dielectric" "X5R"
			(at 0 0 90)
			(unlocked yes)
			(layer "B.Fab")
			(hide yes)
			(effects
				(font
					(size 1 1)
					(thickness 0.15)
				)
				(justify mirror)
			)
		)
		(sheetname "/X710-AT2 power/")
		(sheetfile "x710-at2-power.kicad_sch")
		(attr smd)
		(fp_rect
			(start -0.925 0.47)
			(end 0.925 -0.47)
			(stroke
				(width 0.05)
				(type default)
			)
			(fill no)
			(layer "B.CrtYd")
		)
		(fp_line
			(start 0.504 -0.248)
			(end -0.494 -0.248)
			(stroke
				(width 0.15)
				(type solid)
			)
			(layer "B.Fab")
		)
		(fp_line
			(start -0.494 -0.248)
			(end -0.494 0.25)
			(stroke
				(width 0.15)
				(type solid)
			)
			(layer "B.Fab")
		)
		(fp_line
			(start 0.504 0.25)
			(end 0.504 -0.248)
			(stroke
				(width 0.15)
				(type solid)
			)
			(layer "B.Fab")
		)
		(fp_line
			(start -0.494 0.25)
			(end 0.504 0.25)
			(stroke
				(width 0.15)
				(type solid)
			)
			(layer "B.Fab")
		)
		(pad "1" smd roundrect
			(at -0.48 0 90)
			(size 0.59 0.64)
			(layers "B.Cu" "B.Mask" "B.Paste")
			(roundrect_rratio 0.25)
			(net 28 "GND")
			(pintype "passive")
		)
		(pad "2" smd roundrect
			(at 0.48 0 90)
			(size 0.59 0.64)
			(layers "B.Cu" "B.Mask" "B.Paste")
			(roundrect_rratio 0.25)
			(net 1 "VCCA")
			(pintype "passive")
		)
	)
	(footprint "antmicro-footprints:C_0402_1005Metric"
		(layer "B.Cu")
		(at 83.3 128.5)
		(descr "Capacitor SMD 0402")
		(tags "capacitor SMD 0402")
		(property "Reference" "C53"
			(at -0.85 0.45 0)
			(layer "B.SilkS")
			(effects
				(font
					(size 0.7 0.7)
					(thickness 0.15)
				)
				(justify left bottom mirror)
			)
		)
		(property "Value" "C_1u_25V_0402"
			(at -1.022927 -2.155213 0)
			(layer "B.Fab")
			(hide yes)
			(effects
				(font
					(size 0.7 0.7)
					(thickness 0.15)
				)
				(justify right top mirror)
			)
		)
		(property "Datasheet" "https://www.murata.com/products/productdetail?partno=GRM155R61E105KE11%23"
			(at 0 0 0)
			(layer "B.Fab")
			(hide yes)
			(effects
				(font
					(size 1.27 1.27)
					(thickness 0.15)
				)
				(justify mirror)
			)
		)
		(property "Description" "SMD Multilayer Ceramic Capacitor, 1 µF, 25 V, 0402 [1005 Metric], ± 10%, X5R, GRM Series"
			(at 0 0 0)
			(layer "B.Fab")
			(hide yes)
			(effects
				(font
					(size 1.27 1.27)
					(thickness 0.15)
				)
				(justify mirror)
			)
		)
		(property "MPN" "GRM155R61E105KE11J"
			(at 0 0 0)
			(unlocked yes)
			(layer "B.Fab")
			(hide yes)
			(effects
				(font
					(size 1 1)
					(thickness 0.15)
				)
				(justify mirror)
			)
		)
		(property "Manufacturer" "Murata"
			(at 0 0 0)
			(unlocked yes)
			(layer "B.Fab")
			(hide yes)
			(effects
				(font
					(size 1 1)
					(thickness 0.15)
				)
				(justify mirror)
			)
		)
		(property "License" "Apache-2.0"
			(at 0 0 0)
			(unlocked yes)
			(layer "B.Fab")
			(hide yes)
			(effects
				(font
					(size 1 1)
					(thickness 0.15)
				)
				(justify mirror)
			)
		)
		(property "Author" "Antmicro"
			(at 0 0 0)
			(unlocked yes)
			(layer "B.Fab")
			(hide yes)
			(effects
				(font
					(size 1 1)
					(thickness 0.15)
				)
				(justify mirror)
			)
		)
		(property "Val" "1u"
			(at 0 0 0)
			(unlocked yes)
			(layer "B.Fab")
			(hide yes)
			(effects
				(font
					(size 1 1)
					(thickness 0.15)
				)
				(justify mirror)
			)
		)
		(property "Voltage" "25V"
			(at 0 0 0)
			(unlocked yes)
			(layer "B.Fab")
			(hide yes)
			(effects
				(font
					(size 1 1)
					(thickness 0.15)
				)
				(justify mirror)
			)
		)
		(property "Dielectric" "X5R"
			(at 0 0 0)
			(unlocked yes)
			(layer "B.Fab")
			(hide yes)
			(effects
				(font
					(size 1 1)
					(thickness 0.15)
				)
				(justify mirror)
			)
		)
		(sheetname "/2xRJ45/")
		(sheetfile "2xrj45.kicad_sch")
		(attr smd)
		(fp_rect
			(start -0.925 0.47)
			(end 0.925 -0.47)
			(stroke
				(width 0.05)
				(type default)
			)
			(fill no)
			(layer "B.CrtYd")
		)
		(fp_line
			(start -0.494 -0.248)
			(end -0.494 0.25)
			(stroke
				(width 0.15)
				(type solid)
			)
			(layer "B.Fab")
		)
		(fp_line
			(start -0.494 0.25)
			(end 0.504 0.25)
			(stroke
				(width 0.15)
				(type solid)
			)
			(layer "B.Fab")
		)
		(fp_line
			(start 0.504 -0.248)
			(end -0.494 -0.248)
			(stroke
				(width 0.15)
				(type solid)
			)
			(layer "B.Fab")
		)
		(fp_line
			(start 0.504 0.25)
			(end 0.504 -0.248)
			(stroke
				(width 0.15)
				(type solid)
			)
			(layer "B.Fab")
		)
		(pad "1" smd roundrect
			(at -0.48 0)
			(size 0.59 0.64)
			(layers "B.Cu" "B.Mask" "B.Paste")
			(roundrect_rratio 0.25)
			(net 28 "GND")
			(pintype "passive")
		)
		(pad "2" smd roundrect
			(at 0.48 0)
			(size 0.59 0.64)
			(layers "B.Cu" "B.Mask" "B.Paste")
			(roundrect_rratio 0.25)
			(net 301 "+1V88_CT")
			(pintype "passive")
		)
	)
	(footprint "antmicro-footprints:R_0402_1005Metric"
		(layer "B.Cu")
		(at 109.5 67.6 180)
		(descr "Resistor SMD 0402")
		(tags "resistor SMD 0402")
		(property "Reference" "R167"
			(at -1.44 5.61 0)
			(layer "B.SilkS")
			(effects
				(font
					(size 0.7 0.7)
					(thickness 0.15)
				)
				(justify left bottom mirror)
			)
		)
		(property "Value" "R_0R_0402"
			(at -1.011843 -1.772046 0)
			(layer "B.Fab")
			(hide yes)
			(effects
				(font
					(size 0.7 0.7)
					(thickness 0.15)
				)
				(justify left bottom mirror)
			)
		)
		(property "Datasheet" "https://industrial.panasonic.com/cdbs/www-data/pdf/RDA0000/AOA0000C301.pdf"
			(at 0 0 0)
			(layer "B.Fab")
			(hide yes)
			(effects
				(font
					(size 1.27 1.27)
					(thickness 0.15)
				)
				(justify mirror)
			)
		)
		(property "Description" "SMD Chip Resistor, Jumper, 0 ohm, 100 mW, 0402 [1005 Metric], Thick Film, General Purpose"
			(at 0 0 0)
			(layer "B.Fab")
			(hide yes)
			(effects
				(font
					(size 1.27 1.27)
					(thickness 0.15)
				)
				(justify mirror)
			)
		)
		(property "MPN" "ERJ2GE0R00X"
			(at 0 0 180)
			(unlocked yes)
			(layer "B.Fab")
			(hide yes)
			(effects
				(font
					(size 1 1)
					(thickness 0.15)
				)
				(justify mirror)
			)
		)
		(property "Manufacturer" "Panasonic"
			(at 0 0 180)
			(unlocked yes)
			(layer "B.Fab")
			(hide yes)
			(effects
				(font
					(size 1 1)
					(thickness 0.15)
				)
				(justify mirror)
			)
		)
		(property "License" "Apache-2.0"
			(at 0 0 180)
			(unlocked yes)
			(layer "B.Fab")
			(hide yes)
			(effects
				(font
					(size 1 1)
					(thickness 0.15)
				)
				(justify mirror)
			)
		)
		(property "Author" "Antmicro"
			(at 0 0 180)
			(unlocked yes)
			(layer "B.Fab")
			(hide yes)
			(effects
				(font
					(size 1 1)
					(thickness 0.15)
				)
				(justify mirror)
			)
		)
		(property "Val" "0R"
			(at 0 0 180)
			(unlocked yes)
			(layer "B.Fab")
			(hide yes)
			(effects
				(font
					(size 1 1)
					(thickness 0.15)
				)
				(justify mirror)
			)
		)
		(property "Tolerance" "~"
			(at 0 0 180)
			(unlocked yes)
			(layer "B.Fab")
			(hide yes)
			(effects
				(font
					(size 1 1)
					(thickness 0.15)
				)
				(justify mirror)
			)
		)
		(property "Current" "1A"
			(at 0 0 180)
			(unlocked yes)
			(layer "B.Fab")
			(hide yes)
			(effects
				(font
					(size 1 1)
					(thickness 0.15)
				)
				(justify mirror)
			)
		)
		(sheetname "/OCuLink/")
		(sheetfile "oculink.kicad_sch")
		(attr smd)
		(fp_rect
			(start -0.925 0.47)
			(end 0.925 -0.47)
			(stroke
				(width 0.05)
				(type default)
			)
			(fill no)
			(layer "B.CrtYd")
		)
		(fp_rect
			(start -0.5 0.25)
			(end 0.5 -0.25)
			(stroke
				(width 0.15)
				(type solid)
			)
			(fill no)
			(layer "B.Fab")
		)
		(pad "1" smd roundrect
			(at -0.48 0 180)
			(size 0.59 0.64)
			(layers "B.Cu" "B.Mask" "B.Paste")
			(roundrect_rratio 0.25)
			(net 319 "/OCuLink/~{PE_ RST}_R")
			(pintype "passive")
		)
		(pad "2" smd roundrect
			(at 0.48 0 180)
			(size 0.59 0.64)
			(layers "B.Cu" "B.Mask" "B.Paste")
			(roundrect_rratio 0.25)
			(net 308 "/OCuLink/~{PE_RST}")
			(pintype "passive")
		)
	)
	(footprint "antmicro-footprints:R_0402_1005Metric"
		(layer "B.Cu")
		(at 78.85 101.65 180)
		(descr "Resistor SMD 0402")
		(tags "resistor SMD 0402")
		(property "Reference" "R116"
			(at -0.85 -0.45 0)
			(layer "B.SilkS")
			(effects
				(font
					(size 0.7 0.7)
					(thickness 0.15)
				)
				(justify right bottom mirror)
			)
		)
		(property "Value" "R_1k_0402"
			(at -1.011843 -1.772047 0)
			(layer "B.Fab")
			(hide yes)
			(effects
				(font
					(size 0.7 0.7)
					(thickness 0.15)
				)
				(justify left bottom mirror)
			)
		)
		(property "Datasheet" "https://www.bourns.com/docs/product-datasheets/cr.pdf"
			(at 0 0 0)
			(layer "B.Fab")
			(hide yes)
			(effects
				(font
					(size 1.27 1.27)
					(thickness 0.15)
				)
				(justify mirror)
			)
		)
		(property "Description" "SMD Chip Resistor, 1 kohm, ± 1%, 63 mW, 0402 [1005 Metric], Thick Film, General Purpose"
			(at 0 0 0)
			(layer "B.Fab")
			(hide yes)
			(effects
				(font
					(size 1.27 1.27)
					(thickness 0.15)
				)
				(justify mirror)
			)
		)
		(property "MPN" "CR0402-FX-1001GLF"
			(at 0 0 180)
			(unlocked yes)
			(layer "B.Fab")
			(hide yes)
			(effects
				(font
					(size 1 1)
					(thickness 0.15)
				)
				(justify mirror)
			)
		)
		(property "Manufacturer" "Bourns"
			(at 0 0 180)
			(unlocked yes)
			(layer "B.Fab")
			(hide yes)
			(effects
				(font
					(size 1 1)
					(thickness 0.15)
				)
				(justify mirror)
			)
		)
		(property "License" "Apache-2.0"
			(at 0 0 180)
			(unlocked yes)
			(layer "B.Fab")
			(hide yes)
			(effects
				(font
					(size 1 1)
					(thickness 0.15)
				)
				(justify mirror)
			)
		)
		(property "Author" "Antmicro"
			(at 0 0 180)
			(unlocked yes)
			(layer "B.Fab")
			(hide yes)
			(effects
				(font
					(size 1 1)
					(thickness 0.15)
				)
				(justify mirror)
			)
		)
		(property "Val" "1k"
			(at 0 0 180)
			(unlocked yes)
			(layer "B.Fab")
			(hide yes)
			(effects
				(font
					(size 1 1)
					(thickness 0.15)
				)
				(justify mirror)
			)
		)
		(property "Tolerance" "1%"
			(at 0 0 180)
			(unlocked yes)
			(layer "B.Fab")
			(hide yes)
			(effects
				(font
					(size 1 1)
					(thickness 0.15)
				)
				(justify mirror)
			)
		)
		(sheetname "/X710-AT2 Misc/")
		(sheetfile "x710-at2-mics.kicad_sch")
		(attr smd)
		(fp_rect
			(start -0.925 0.47)
			(end 0.925 -0.47)
			(stroke
				(width 0.05)
				(type default)
			)
			(fill no)
			(layer "B.CrtYd")
		)
		(fp_rect
			(start -0.5 0.25)
			(end 0.5 -0.25)
			(stroke
				(width 0.15)
				(type solid)
			)
			(fill no)
			(layer "B.Fab")
		)
		(pad "1" smd roundrect
			(at -0.48 0 180)
			(size 0.59 0.64)
			(layers "B.Cu" "B.Mask" "B.Paste")
			(roundrect_rratio 0.25)
			(net 112 "/X710-AT2 Misc/RSVDL33")
			(pintype "passive")
		)
		(pad "2" smd roundrect
			(at 0.48 0 180)
			(size 0.59 0.64)
			(layers "B.Cu" "B.Mask" "B.Paste")
			(roundrect_rratio 0.25)
			(net 18 "+1V88")
			(pintype "passive")
		)
	)
	(footprint "antmicro-footprints:TP_SMD_1mm"
		(layer "B.Cu")
		(at 82.49 72.3 -90)
		(property "Reference" "TP29"
			(at -1.87 8.478102 90)
			(layer "B.SilkS")
			(effects
				(font
					(size 0.7 0.7)
					(thickness 0.15)
				)
				(justify left bottom mirror)
			)
		)
		(property "Value" "TP_1mm_SMD"
			(at 0 -1.4 90)
			(layer "B.Fab")
			(hide yes)
			(effects
				(font
					(size 0.7 0.7)
					(thickness 0.15)
				)
				(justify left bottom mirror)
			)
		)
		(property "Description" "Test point 1mm SMD"
			(at 0 0 90)
			(layer "B.Fab")
			(hide yes)
			(effects
				(font
					(size 1.27 1.27)
					(thickness 0.15)
				)
				(justify mirror)
			)
		)
		(property "MPN" ""
			(at 0 0 90)
			(unlocked yes)
			(layer "B.Fab")
			(hide yes)
			(effects
				(font
					(size 1 1)
					(thickness 0.15)
				)
				(justify mirror)
			)
		)
		(property "Manufacturer" ""
			(at 0 0 90)
			(unlocked yes)
			(layer "B.Fab")
			(hide yes)
			(effects
				(font
					(size 1 1)
					(thickness 0.15)
				)
				(justify mirror)
			)
		)
		(property "Author" "Antmicro"
			(at 0 0 90)
			(unlocked yes)
			(layer "B.Fab")
			(hide yes)
			(effects
				(font
					(size 1 1)
					(thickness 0.15)
				)
				(justify mirror)
			)
		)
		(property "License" "Apache-2.0"
			(at 0 0 90)
			(unlocked yes)
			(layer "B.Fab")
			(hide yes)
			(effects
				(font
					(size 1 1)
					(thickness 0.15)
				)
				(justify mirror)
			)
		)
		(sheetname "/Power/")
		(sheetfile "power.kicad_sch")
		(attr exclude_from_pos_files exclude_from_bom)
		(fp_circle
			(center 0 0)
			(end 0.6 0)
			(stroke
				(width 0.05)
				(type default)
			)
			(fill no)
			(layer "B.CrtYd")
		)
		(pad "1" smd circle
			(at 0 0 270)
			(size 1 1)
			(layers "B.Cu" "B.Mask")
			(net 314 "VCC")
			(pinfunction "1")
			(pintype "passive")
		)
	)
)
